(kicad_pcb
	(version 20260206)
	(generator "pcbnew")
	(generator_version "10.0")
	(general
		(thickness 1.6)
		(legacy_teardrops no)
	)
	(paper "A4")
	(title_block
		(title "03242023_DA0F0TMBIJ0_F0T_Motherboard_J_brd_V01_OCP.brd")
		(comment 1 "Grand Teton / footprints 4705-4710 of 6105")
	)
	(layers
		(0 "F.Cu" signal "TOP")
		(4 "In1.Cu" signal "GND")
		(6 "In2.Cu" signal "IN1")
		(8 "In3.Cu" signal "GND1")
		(10 "In4.Cu" signal "IN2")
		(12 "In5.Cu" signal "GND2")
		(14 "In6.Cu" signal "IN3")
		(16 "In7.Cu" signal "GND3")
		(18 "In8.Cu" signal "VCC")
		(20 "In9.Cu" signal "VCC1")
		(22 "In10.Cu" signal "GND4")
		(24 "In11.Cu" signal "IN4")
		(26 "In12.Cu" signal "GND5")
		(28 "In13.Cu" signal "IN5")
		(30 "In14.Cu" signal "GND6")
		(32 "In15.Cu" signal "IN6")
		(34 "In16.Cu" signal "GND7")
		(2 "B.Cu" signal "BOTTOM")
		(9 "F.Adhes" user "F.Adhesive")
		(11 "B.Adhes" user "B.Adhesive")
		(13 "F.Paste" user "Package Geometry/Pastemask Top")
		(15 "B.Paste" user "Package Geometry/Pastemask Bottom")
		(5 "F.SilkS" user "Ref Des/Silkscreen Top")
		(7 "B.SilkS" user "Ref Des/Silkscreen Bottom")
		(1 "F.Mask" user "Board Geometry/Soldermask Top")
		(3 "B.Mask" user "Board Geometry/Soldermask Bottom")
		(17 "Dwgs.User" user "User.Drawings")
		(19 "Cmts.User" user "User.Comments")
		(21 "Eco1.User" user "User.Eco1")
		(23 "Eco2.User" user "User.Eco2")
		(25 "Edge.Cuts" user "Board Geometry/Outline")
		(27 "Margin" user)
		(31 "F.CrtYd" user "Package Geometry/Place Bound Top")
		(29 "B.CrtYd" user "Package Geometry/Place Bound Bottom")
		(35 "F.Fab" user "Ref Des/Assembly Top")
		(33 "B.Fab" user "Ref Des/Assembly Bottom")
	)
	(footprint ""
		(layer "B.Cu")
		(at 500.77497 -427.51502 180)
		(property "Reference" "DB13"
			(at 2.443988 -8.440928 270)
			(unlocked yes)
			(layer "B.SilkS")
			(effects
				(font
					(size 0.7874 0.5842)
					(thickness 0.1524)
				)
				(justify left mirror)
			)
		)
		(property "Value" ""
			(at 0 0 0)
			(layer "B.Fab")
			(effects
				(font
					(size 1.27 1.27)
				)
				(justify mirror)
			)
		)
		(duplicate_pad_numbers_are_jumpers no)
		(fp_line
			(start 3.330702 -4.771136)
			(end -3.330702 -4.771136)
			(stroke
				(width 0.1524)
				(type default)
			)
			(layer "B.SilkS")
		)
		(fp_line
			(start 0 4.011168)
			(end 3.330702 -4.771136)
			(stroke
				(width 0.1524)
				(type default)
			)
			(layer "B.SilkS")
		)
		(fp_line
			(start -3.330702 -4.771136)
			(end 0 4.011168)
			(stroke
				(width 0.1524)
				(type default)
			)
			(layer "B.SilkS")
		)
		(fp_line
			(start 3.330702 -4.771136)
			(end -3.330702 -4.771136)
			(stroke
				(width 0.1)
				(type default)
			)
			(layer "B.Fab")
		)
		(fp_line
			(start 0 4.011168)
			(end 3.330702 -4.771136)
			(stroke
				(width 0.1)
				(type default)
			)
			(layer "B.Fab")
		)
		(fp_line
			(start -3.330702 -4.771136)
			(end 0 4.011168)
			(stroke
				(width 0.1)
				(type default)
			)
			(layer "B.Fab")
		)
		(pad "1" thru_hole circle
			(at 0 0)
			(size 2.159 2.159)
			(drill 1.7018)
			(layers "*.Cu" "*.Mask")
			(remove_unused_layers no)
			(net "T1_GND")
			(clearance 0.0254)
			(thermal_gap 0.0254)
		)
		(pad "2" thru_hole circle
			(at 1.27 -3.348736)
			(size 2.159 2.159)
			(drill 1.7018)
			(layers "*.Cu" "*.Mask")
			(remove_unused_layers no)
			(net "TDR_SE_40_OHM_IN5")
			(clearance 0.0254)
			(thermal_gap 0.0254)
		)
		(pad "3" thru_hole circle
			(at -1.27 -3.348736)
			(size 2.159 2.159)
			(drill 1.7018)
			(layers "*.Cu" "*.Mask")
			(remove_unused_layers no)
			(net "TDR_SE_40_OHM_IN5")
			(clearance 0.0254)
			(thermal_gap 0.0254)
		)
	)
	(footprint ""
		(layer "B.Cu")
		(at 164.64788 -122.646948)
		(property "Reference" "R1414"
			(at 0 0 0)
			(layer "B.SilkS")
			(hide yes)
			(effects
				(font
					(size 1.27 1.27)
				)
				(justify mirror)
			)
		)
		(property "Value" ""
			(at 0 0 0)
			(layer "B.Fab")
			(effects
				(font
					(size 1.27 1.27)
				)
				(justify mirror)
			)
		)
		(duplicate_pad_numbers_are_jumpers no)
		(fp_line
			(start -0.7874 -0.4064)
			(end -0.7874 0.4064)
			(stroke
				(width 0.1524)
				(type default)
			)
			(layer "B.SilkS")
		)
		(fp_line
			(start -0.7874 0.4064)
			(end 0.7874 0.4064)
			(stroke
				(width 0.1524)
				(type default)
			)
			(layer "B.SilkS")
		)
		(fp_line
			(start 0.7874 -0.4064)
			(end -0.7874 -0.4064)
			(stroke
				(width 0.1524)
				(type default)
			)
			(layer "B.SilkS")
		)
		(fp_line
			(start 0.7874 0.4064)
			(end 0.7874 -0.4064)
			(stroke
				(width 0.1524)
				(type default)
			)
			(layer "B.SilkS")
		)
		(fp_line
			(start -0.67945 -0.3048)
			(end -0.67945 0.3048)
			(stroke
				(width 0.1)
				(type default)
			)
			(layer "B.Fab")
		)
		(fp_line
			(start -0.67945 0.3048)
			(end -0.120396 0.3048)
			(stroke
				(width 0.1)
				(type default)
			)
			(layer "B.Fab")
		)
		(fp_line
			(start -0.12065 -0.3048)
			(end -0.67945 -0.3048)
			(stroke
				(width 0.1)
				(type default)
			)
			(layer "B.Fab")
		)
		(fp_line
			(start -0.12065 -0.2794)
			(end -0.12065 -0.3048)
			(stroke
				(width 0.1)
				(type default)
			)
			(layer "B.Fab")
		)
		(fp_line
			(start -0.120396 0.2794)
			(end 0.12065 0.2794)
			(stroke
				(width 0.1)
				(type default)
			)
			(layer "B.Fab")
		)
		(fp_line
			(start -0.120396 0.3048)
			(end -0.120396 0.2794)
			(stroke
				(width 0.1)
				(type default)
			)
			(layer "B.Fab")
		)
		(fp_line
			(start 0.12065 -0.305054)
			(end 0.12065 -0.2794)
			(stroke
				(width 0.1)
				(type default)
			)
			(layer "B.Fab")
		)
		(fp_line
			(start 0.12065 -0.2794)
			(end -0.12065 -0.2794)
			(stroke
				(width 0.1)
				(type default)
			)
			(layer "B.Fab")
		)
		(fp_line
			(start 0.12065 0.2794)
			(end 0.12065 0.3048)
			(stroke
				(width 0.1)
				(type default)
			)
			(layer "B.Fab")
		)
		(fp_line
			(start 0.12065 0.3048)
			(end 0.67945 0.3048)
			(stroke
				(width 0.1)
				(type default)
			)
			(layer "B.Fab")
		)
		(fp_line
			(start 0.67945 -0.305054)
			(end 0.12065 -0.305054)
			(stroke
				(width 0.1)
				(type default)
			)
			(layer "B.Fab")
		)
		(fp_line
			(start 0.67945 0.3048)
			(end 0.67945 -0.305054)
			(stroke
				(width 0.1)
				(type default)
			)
			(layer "B.Fab")
		)
		(pad "1" smd circle
			(at 0.40005 0 180)
			(size 0 0)
			(layers "B.Cu" "B.Mask" "B.Paste")
			(net "FM_PVCCD_HV_CPU1_EN")
		)
		(pad "2" smd circle
			(at -0.40005 0 180)
			(size 0 0)
			(layers "B.Cu" "B.Mask" "B.Paste")
			(net "GND")
		)
	)
	(footprint ""
		(layer "B.Cu")
		(at 425.917614 -321.549776 -90)
		(property "Reference" "C37"
			(at 0 0 90)
			(layer "B.SilkS")
			(hide yes)
			(effects
				(font
					(size 1.27 1.27)
				)
				(justify mirror)
			)
		)
		(property "Value" ""
			(at 0 0 90)
			(layer "B.Fab")
			(effects
				(font
					(size 1.27 1.27)
				)
				(justify mirror)
			)
		)
		(duplicate_pad_numbers_are_jumpers no)
		(fp_line
			(start -1.524 0.762)
			(end 1.524 0.762)
			(stroke
				(width 0.1524)
				(type default)
			)
			(layer "B.SilkS")
		)
		(fp_line
			(start 1.524 0.762)
			(end 1.524 -0.762)
			(stroke
				(width 0.1524)
				(type default)
			)
			(layer "B.SilkS")
		)
		(fp_line
			(start -1.524 -0.762)
			(end -1.524 0.762)
			(stroke
				(width 0.1524)
				(type default)
			)
			(layer "B.SilkS")
		)
		(fp_line
			(start 1.524 -0.762)
			(end -1.524 -0.762)
			(stroke
				(width 0.1524)
				(type default)
			)
			(layer "B.SilkS")
		)
		(fp_line
			(start -1.1049 0.724916)
			(end -1.1049 -0.724916)
			(stroke
				(width 0.1)
				(type default)
			)
			(layer "B.Fab")
		)
		(fp_line
			(start 1.1049 0.724916)
			(end -1.1049 0.724916)
			(stroke
				(width 0.1)
				(type default)
			)
			(layer "B.Fab")
		)
		(fp_line
			(start -1.1049 -0.724916)
			(end 1.1049 -0.724916)
			(stroke
				(width 0.1)
				(type default)
			)
			(layer "B.Fab")
		)
		(fp_line
			(start 1.1049 -0.724916)
			(end 1.1049 0.724916)
			(stroke
				(width 0.1)
				(type default)
			)
			(layer "B.Fab")
		)
		(pad "1" smd rect
			(at 0.889 0 270)
			(size 1.016 1.27)
			(layers "B.Cu" "B.Mask" "B.Paste")
			(net "P12V_S3_AUX_CPU0_NVDIMM")
		)
		(pad "2" smd rect
			(at -0.889 0 270)
			(size 1.016 1.27)
			(layers "B.Cu" "B.Mask" "B.Paste")
			(net "GND")
		)
	)
	(footprint ""
		(layer "B.Cu")
		(at 27.7368 -162.270948 -90)
		(property "Reference" "PR4255"
			(at 0 0 90)
			(layer "B.SilkS")
			(hide yes)
			(effects
				(font
					(size 1.27 1.27)
				)
				(justify mirror)
			)
		)
		(property "Value" ""
			(at 0 0 90)
			(layer "B.Fab")
			(effects
				(font
					(size 1.27 1.27)
				)
				(justify mirror)
			)
		)
		(duplicate_pad_numbers_are_jumpers no)
		(fp_line
			(start -0.7874 0.4064)
			(end 0.7874 0.4064)
			(stroke
				(width 0.1524)
				(type default)
			)
			(layer "B.SilkS")
		)
		(fp_line
			(start 0.7874 0.4064)
			(end 0.7874 -0.4064)
			(stroke
				(width 0.1524)
				(type default)
			)
			(layer "B.SilkS")
		)
		(fp_line
			(start -0.7874 -0.4064)
			(end -0.7874 0.4064)
			(stroke
				(width 0.1524)
				(type default)
			)
			(layer "B.SilkS")
		)
		(fp_line
			(start 0.7874 -0.4064)
			(end -0.7874 -0.4064)
			(stroke
				(width 0.1524)
				(type default)
			)
			(layer "B.SilkS")
		)
		(fp_line
			(start -0.67945 0.3048)
			(end -0.120396 0.3048)
			(stroke
				(width 0.1)
				(type default)
			)
			(layer "B.Fab")
		)
		(fp_line
			(start -0.120396 0.3048)
			(end -0.120396 0.2794)
			(stroke
				(width 0.1)
				(type default)
			)
			(layer "B.Fab")
		)
		(fp_line
			(start 0.12065 0.3048)
			(end 0.67945 0.3048)
			(stroke
				(width 0.1)
				(type default)
			)
			(layer "B.Fab")
		)
		(fp_line
			(start 0.67945 0.3048)
			(end 0.67945 -0.305054)
			(stroke
				(width 0.1)
				(type default)
			)
			(layer "B.Fab")
		)
		(fp_line
			(start -0.120396 0.2794)
			(end 0.12065 0.2794)
			(stroke
				(width 0.1)
				(type default)
			)
			(layer "B.Fab")
		)
		(fp_line
			(start 0.12065 0.2794)
			(end 0.12065 0.3048)
			(stroke
				(width 0.1)
				(type default)
			)
			(layer "B.Fab")
		)
		(fp_line
			(start -0.12065 -0.2794)
			(end -0.12065 -0.3048)
			(stroke
				(width 0.1)
				(type default)
			)
			(layer "B.Fab")
		)
		(fp_line
			(start 0.12065 -0.2794)
			(end -0.12065 -0.2794)
			(stroke
				(width 0.1)
				(type default)
			)
			(layer "B.Fab")
		)
		(fp_line
			(start -0.67945 -0.3048)
			(end -0.67945 0.3048)
			(stroke
				(width 0.1)
				(type default)
			)
			(layer "B.Fab")
		)
		(fp_line
			(start -0.12065 -0.3048)
			(end -0.67945 -0.3048)
			(stroke
				(width 0.1)
				(type default)
			)
			(layer "B.Fab")
		)
		(fp_line
			(start 0.12065 -0.305054)
			(end 0.12065 -0.2794)
			(stroke
				(width 0.1)
				(type default)
			)
			(layer "B.Fab")
		)
		(fp_line
			(start 0.67945 -0.305054)
			(end 0.12065 -0.305054)
			(stroke
				(width 0.1)
				(type default)
			)
			(layer "B.Fab")
		)
		(pad "1" smd circle
			(at 0.40005 0 90)
			(size 0 0)
			(layers "B.Cu" "B.Mask" "B.Paste")
			(net "NC_PVCCD_HV_CPU1_ACSP6")
		)
		(pad "2" smd circle
			(at -0.40005 0 90)
			(size 0 0)
			(layers "B.Cu" "B.Mask" "B.Paste")
			(net "GND")
		)
	)
	(footprint ""
		(layer "B.Cu")
		(at 103.596694 -237.794292 -90)
		(property "Reference" "C1389"
			(at 0 0 90)
			(layer "B.SilkS")
			(hide yes)
			(effects
				(font
					(size 1.27 1.27)
				)
				(justify mirror)
			)
		)
		(property "Value" ""
			(at 0 0 90)
			(layer "B.Fab")
			(effects
				(font
					(size 1.27 1.27)
				)
				(justify mirror)
			)
		)
		(duplicate_pad_numbers_are_jumpers no)
		(fp_line
			(start -1.2954 0.5842)
			(end 1.2954 0.5842)
			(stroke
				(width 0.1524)
				(type default)
			)
			(layer "B.SilkS")
		)
		(fp_line
			(start 1.2954 0.5842)
			(end 1.2954 -0.5842)
			(stroke
				(width 0.1524)
				(type default)
			)
			(layer "B.SilkS")
		)
		(fp_line
			(start -1.2954 -0.5842)
			(end -1.2954 0.5842)
			(stroke
				(width 0.1524)
				(type default)
			)
			(layer "B.SilkS")
		)
		(fp_line
			(start 0 -0.5842)
			(end 0 0.5842)
			(stroke
				(width 0.1524)
				(type default)
			)
			(layer "B.SilkS")
		)
		(fp_line
			(start 1.2954 -0.5842)
			(end -1.2954 -0.5842)
			(stroke
				(width 0.1524)
				(type default)
			)
			(layer "B.SilkS")
		)
		(fp_line
			(start -0.8636 0.4572)
			(end 0.8636 0.4572)
			(stroke
				(width 0.1)
				(type default)
			)
			(layer "B.Fab")
		)
		(fp_line
			(start 0.8636 0.4572)
			(end 0.8636 0.4064)
			(stroke
				(width 0.1)
				(type default)
			)
			(layer "B.Fab")
		)
		(fp_line
			(start -1.1938 0.4064)
			(end -0.8636 0.4064)
			(stroke
				(width 0.1)
				(type default)
			)
			(layer "B.Fab")
		)
		(fp_line
			(start -0.8636 0.4064)
			(end -0.8636 0.4572)
			(stroke
				(width 0.1)
				(type default)
			)
			(layer "B.Fab")
		)
		(fp_line
			(start 0.8636 0.4064)
			(end 1.1938 0.4064)
			(stroke
				(width 0.1)
				(type default)
			)
			(layer "B.Fab")
		)
		(fp_line
			(start 1.1938 0.4064)
			(end 1.1938 -0.4064)
			(stroke
				(width 0.1)
				(type default)
			)
			(layer "B.Fab")
		)
		(fp_line
			(start -1.1938 -0.4064)
			(end -1.1938 0.4064)
			(stroke
				(width 0.1)
				(type default)
			)
			(layer "B.Fab")
		)
		(fp_line
			(start -0.8636 -0.4064)
			(end -1.1938 -0.4064)
			(stroke
				(width 0.1)
				(type default)
			)
			(layer "B.Fab")
		)
		(fp_line
			(start 0.8636 -0.4064)
			(end 0.8636 -0.4572)
			(stroke
				(width 0.1)
				(type default)
			)
			(layer "B.Fab")
		)
		(fp_line
			(start 1.1938 -0.4064)
			(end 0.8636 -0.4064)
			(stroke
				(width 0.1)
				(type default)
			)
			(layer "B.Fab")
		)
		(fp_line
			(start -0.8636 -0.4572)
			(end -0.8636 -0.4064)
			(stroke
				(width 0.1)
				(type default)
			)
			(layer "B.Fab")
		)
		(fp_line
			(start 0.8636 -0.4572)
			(end -0.8636 -0.4572)
			(stroke
				(width 0.1)
				(type default)
			)
			(layer "B.Fab")
		)
		(pad "1" smd rect
			(at 0.7366 0 180)
			(size 0.7112 0.8128)
			(layers "B.Cu" "B.Mask" "B.Paste")
			(net "PVNN_MAIN_CPU1")
		)
		(pad "2" smd rect
			(at -0.7366 0 180)
			(size 0.7112 0.8128)
			(layers "B.Cu" "B.Mask" "B.Paste")
			(net "GND")
		)
	)
	(footprint ""
		(layer "B.Cu")
		(at 423.807382 -137.07872 180)
		(property "Reference" "PC1271"
			(at 0 0 0)
			(layer "B.SilkS")
			(hide yes)
			(effects
				(font
					(size 1.27 1.27)
				)
				(justify mirror)
			)
		)
		(property "Value" ""
			(at 0 0 0)
			(layer "B.Fab")
			(effects
				(font
					(size 1.27 1.27)
				)
				(justify mirror)
			)
		)
		(duplicate_pad_numbers_are_jumpers no)
		(fp_line
			(start 0.7874 0.4064)
			(end 0.7874 -0.4064)
			(stroke
				(width 0.1524)
				(type default)
			)
			(layer "B.SilkS")
		)
		(fp_line
			(start 0.7874 -0.4064)
			(end -0.7874 -0.4064)
			(stroke
				(width 0.1524)
				(type default)
			)
			(layer "B.SilkS")
		)
		(fp_line
			(start -0.7874 0.4064)
			(end 0.7874 0.4064)
			(stroke
				(width 0.1524)
				(type default)
			)
			(layer "B.SilkS")
		)
		(fp_line
			(start -0.7874 -0.4064)
			(end -0.7874 0.4064)
			(stroke
				(width 0.1524)
				(type default)
			)
			(layer "B.SilkS")
		)
		(fp_line
			(start 0.67945 0.3048)
			(end 0.67945 -0.305054)
			(stroke
				(width 0.1)
				(type default)
			)
			(layer "B.Fab")
		)
		(fp_line
			(start 0.67945 -0.305054)
			(end 0.12065 -0.305054)
			(stroke
				(width 0.1)
				(type default)
			)
			(layer "B.Fab")
		)
		(fp_line
			(start 0.12065 0.3048)
			(end 0.67945 0.3048)
			(stroke
				(width 0.1)
				(type default)
			)
			(layer "B.Fab")
		)
		(fp_line
			(start 0.12065 0.2794)
			(end 0.12065 0.3048)
			(stroke
				(width 0.1)
				(type default)
			)
			(layer "B.Fab")
		)
		(fp_line
			(start 0.12065 -0.2794)
			(end -0.12065 -0.2794)
			(stroke
				(width 0.1)
				(type default)
			)
			(layer "B.Fab")
		)
		(fp_line
			(start 0.12065 -0.305054)
			(end 0.12065 -0.2794)
			(stroke
				(width 0.1)
				(type default)
			)
			(layer "B.Fab")
		)
		(fp_line
			(start -0.120396 0.3048)
			(end -0.120396 0.2794)
			(stroke
				(width 0.1)
				(type default)
			)
			(layer "B.Fab")
		)
		(fp_line
			(start -0.120396 0.2794)
			(end 0.12065 0.2794)
			(stroke
				(width 0.1)
				(type default)
			)
			(layer "B.Fab")
		)
		(fp_line
			(start -0.12065 -0.2794)
			(end -0.12065 -0.3048)
			(stroke
				(width 0.1)
				(type default)
			)
			(layer "B.Fab")
		)
		(fp_line
			(start -0.12065 -0.3048)
			(end -0.67945 -0.3048)
			(stroke
				(width 0.1)
				(type default)
			)
			(layer "B.Fab")
		)
		(fp_line
			(start -0.67945 0.3048)
			(end -0.120396 0.3048)
			(stroke
				(width 0.1)
				(type default)
			)
			(layer "B.Fab")
		)
		(fp_line
			(start -0.67945 -0.3048)
			(end -0.67945 0.3048)
			(stroke
				(width 0.1)
				(type default)
			)
			(layer "B.Fab")
		)
		(pad "1" smd circle
			(at 0.40005 0)
			(size 0 0)
			(layers "B.Cu" "B.Mask" "B.Paste")
			(net "PVCCFA_EHV_CPU0_BTSEN")
		)
		(pad "2" smd circle
			(at -0.40005 0)
			(size 0 0)
			(layers "B.Cu" "B.Mask" "B.Paste")
			(net "GND")
		)
	)
)
